(kicad_pcb
	(version 20260206)
	(generator "pcbnew")
	(generator_version "10.0")
	(general
		(thickness 1.6)
		(legacy_teardrops no)
	)
	(paper "A4")
	(title_block
		(title "panther-plus-userver — 13130-1b_20150205.brd")
		(comment 1 "Honey Badger (Wiwynn) / footprint 406 of 1509 (DIMM2), pads 86-92 of 210")
	)
	(layers
		(0 "F.Cu" signal "TOP")
		(4 "In1.Cu" signal "L2")
		(6 "In2.Cu" signal "L3")
		(8 "In3.Cu" signal "L4")
		(10 "In4.Cu" signal "L5")
		(12 "In5.Cu" signal "L6")
		(14 "In6.Cu" signal "L7")
		(16 "In7.Cu" signal "L8")
		(18 "In8.Cu" signal "L9")
		(20 "In9.Cu" signal "L10")
		(22 "In10.Cu" signal "L11")
		(2 "B.Cu" signal "BOTTOM")
		(9 "F.Adhes" user "F.Adhesive")
		(11 "B.Adhes" user "B.Adhesive")
		(13 "F.Paste" user "Package Geometry/Pastemask Top")
		(15 "B.Paste" user "Package Geometry/Pastemask Bottom")
		(5 "F.SilkS" user "Ref Des/Silkscreen Top")
		(7 "B.SilkS" user "Ref Des/Silkscreen Bottom")
		(1 "F.Mask" user "Board Geometry/Soldermask Top")
		(3 "B.Mask" user "Board Geometry/Soldermask Bottom")
		(17 "Dwgs.User" user "User.Drawings")
		(19 "Cmts.User" user "User.Comments")
		(21 "Eco1.User" user "User.Eco1")
		(23 "Eco2.User" user "User.Eco2")
		(25 "Edge.Cuts" user "Board Geometry/Outline")
		(27 "Margin" user)
		(31 "F.CrtYd" user "Package Geometry/Place Bound Top")
		(29 "B.CrtYd" user "Package Geometry/Place Bound Bottom")
		(35 "F.Fab" user "Ref Des/Assembly Top")
		(33 "B.Fab" user "Ref Des/Assembly Bottom")
	)
	(footprint ""
		(layer "F.Cu")
		(at 158.500064 -66.699892 180)
		(property "Reference" "DIMM2"
			(at 0 0 180)
			(layer "F.SilkS")
			(hide yes)
			(effects
				(font
					(size 1.27 1.27)
				)
			)
		)
		(property "Value" "DDR3-204P-174-COLAY-1-GP"
			(at -40.682164 -17.468088 180)
			(unlocked yes)
			(layer "F.Fab")
			(hide yes)
			(effects
				(font
					(size 1.016 1.016)
					(thickness 0.1524)
				)
			)
		)
		(property "Device Type" "AS0A626-H8SN-7H-COLAY-1"
			(at -40.682164 -18.992088 180)
			(unlocked yes)
			(layer "F.Fab")
			(hide yes)
			(effects
				(font
					(size 1.016 1.016)
					(thickness 0.1524)
				)
			)
		)
		(duplicate_pad_numbers_are_jumpers no)
		(pad "84" smd custom
			(at -4.350004 -4.106672 180)
			(size 0.1143 0.1143)
			(layers "F.Cu" "F.Mask" "F.Paste")
			(net "DDR3_M_A_VREF_CA")
			(options
				(clearance outline)
				(anchor circle)
			)
			(primitives
				(gr_poly
					(pts
						(xy 0 0.9017) (xy -0.03175 0.89916) (xy -0.0635 0.889) (xy -0.09144 0.87376) (xy -0.11684 0.85344)
						(xy -0.13716 0.82804) (xy -0.1524 0.8001) (xy -0.16256 0.76835) (xy -0.1651 0.7366) (xy -0.1651 0.19685)
						(xy -0.17272 0.18923) (xy -0.17907 0.18034) (xy -0.18669 0.17145) (xy -0.19177 0.16256) (xy -0.19812 0.15367)
						(xy -0.20828 0.13335) (xy -0.21971 0.10287) (xy -0.22225 0.09271) (xy -0.22479 0.08128) (xy -0.22606 0.07112)
						(xy -0.2286 0.05969) (xy -0.2286 0.01651) (xy -0.22606 0.00508) (xy -0.22479 -0.00508) (xy -0.22225 -0.01651)
						(xy -0.21971 -0.02667) (xy -0.20828 -0.05715) (xy -0.19812 -0.07747) (xy -0.19177 -0.08636) (xy -0.18669 -0.09525)
						(xy -0.17907 -0.10414) (xy -0.17272 -0.11303) (xy -0.1651 -0.12065) (xy -0.1651 -0.7366) (xy -0.16256 -0.76835)
						(xy -0.1524 -0.8001) (xy -0.13716 -0.82804) (xy -0.11684 -0.85344) (xy -0.09144 -0.87376) (xy -0.0635 -0.889)
						(xy -0.03175 -0.89916) (xy 0 -0.9017) (xy 0.03175 -0.89916) (xy 0.0635 -0.889) (xy 0.09144 -0.87376)
						(xy 0.11684 -0.85344) (xy 0.13716 -0.82804) (xy 0.1524 -0.8001) (xy 0.16256 -0.76835) (xy 0.1651 -0.7366)
						(xy 0.1651 -0.11938) (xy 0.17272 -0.11176) (xy 0.19812 -0.0762) (xy 0.2032 -0.06604) (xy 0.20701 -0.05715)
						(xy 0.21209 -0.04699) (xy 0.2159 -0.03683) (xy 0.21844 -0.02667) (xy 0.22225 -0.01524) (xy 0.22352 -0.00508)
						(xy 0.22606 0.00508) (xy 0.22733 0.01651) (xy 0.22733 0.02667) (xy 0.2286 0.0381) (xy 0.22733 0.04953)
						(xy 0.22733 0.05969) (xy 0.22606 0.07112) (xy 0.22352 0.08128) (xy 0.22225 0.09144) (xy 0.21844 0.10287)
						(xy 0.2159 0.11303) (xy 0.21209 0.12319) (xy 0.20701 0.13335) (xy 0.2032 0.14224) (xy 0.19812 0.1524)
						(xy 0.17272 0.18796) (xy 0.1651 0.19558) (xy 0.1651 0.7366) (xy 0.16256 0.76835) (xy 0.1524 0.8001)
						(xy 0.13716 0.82804) (xy 0.11684 0.85344) (xy 0.09144 0.87376) (xy 0.0635 0.889) (xy 0.03175 0.89916)
					)
					(width 0)
					(fill yes)
				)
			)
		)
		(pad "85" smd custom
			(at -4.05003 4.106672 180)
			(size 0.1143 0.1143)
			(layers "F.Cu" "F.Mask" "F.Paste")
			(net "PV_VDDR")
			(options
				(clearance outline)
				(anchor circle)
			)
			(primitives
				(gr_poly
					(pts
						(xy 0 0.9017) (xy -0.03175 0.89916) (xy -0.0635 0.889) (xy -0.09144 0.87376) (xy -0.11684 0.85344)
						(xy -0.13716 0.82804) (xy -0.1524 0.8001) (xy -0.16256 0.76835) (xy -0.1651 0.7366) (xy -0.1651 -0.13462)
						(xy -0.17272 -0.14224) (xy -0.19812 -0.1778) (xy -0.2032 -0.18796) (xy -0.20701 -0.19685) (xy -0.21209 -0.20701)
						(xy -0.2159 -0.21717) (xy -0.21844 -0.22733) (xy -0.22225 -0.23876) (xy -0.22352 -0.24892) (xy -0.22606 -0.25908)
						(xy -0.22733 -0.27051) (xy -0.22733 -0.28067) (xy -0.2286 -0.2921) (xy -0.22733 -0.30353) (xy -0.22733 -0.31369)
						(xy -0.22606 -0.32512) (xy -0.22352 -0.33528) (xy -0.22225 -0.34544) (xy -0.21844 -0.35687) (xy -0.2159 -0.36703)
						(xy -0.21209 -0.37719) (xy -0.20701 -0.38735) (xy -0.2032 -0.39624) (xy -0.19812 -0.4064) (xy -0.17272 -0.44196)
						(xy -0.1651 -0.44958) (xy -0.1651 -0.7366) (xy -0.16256 -0.76835) (xy -0.1524 -0.8001) (xy -0.13716 -0.82804)
						(xy -0.11684 -0.85344) (xy -0.09144 -0.87376) (xy -0.0635 -0.889) (xy -0.03175 -0.89916) (xy 0 -0.9017)
						(xy 0.03175 -0.89916) (xy 0.0635 -0.889) (xy 0.09144 -0.87376) (xy 0.11684 -0.85344) (xy 0.13716 -0.82804)
						(xy 0.1524 -0.8001) (xy 0.16256 -0.76835) (xy 0.1651 -0.7366) (xy 0.1651 -0.44958) (xy 0.17272 -0.44196)
						(xy 0.19812 -0.4064) (xy 0.2032 -0.39624) (xy 0.20701 -0.38735) (xy 0.21209 -0.37719) (xy 0.2159 -0.36703)
						(xy 0.21844 -0.35687) (xy 0.22225 -0.34544) (xy 0.22352 -0.33528) (xy 0.22606 -0.32512) (xy 0.22733 -0.31369)
						(xy 0.22733 -0.30353) (xy 0.2286 -0.2921) (xy 0.22733 -0.28067) (xy 0.22733 -0.27051) (xy 0.22606 -0.25908)
						(xy 0.22352 -0.24892) (xy 0.22225 -0.23876) (xy 0.21844 -0.22733) (xy 0.2159 -0.21717) (xy 0.21209 -0.20701)
						(xy 0.20701 -0.19685) (xy 0.2032 -0.18796) (xy 0.19812 -0.1778) (xy 0.17272 -0.14224) (xy 0.1651 -0.13462)
						(xy 0.1651 0.7366) (xy 0.16256 0.76835) (xy 0.1524 0.8001) (xy 0.13716 0.82804) (xy 0.11684 0.85344)
						(xy 0.09144 0.87376) (xy 0.0635 0.889) (xy 0.03175 0.89916)
					)
					(width 0)
					(fill yes)
				)
			)
		)
		(pad "86" smd custom
			(at -3.750056 -4.106672 180)
			(size 0.1143 0.1143)
			(layers "F.Cu" "F.Mask" "F.Paste")
			(net "PV_VDDR")
			(options
				(clearance outline)
				(anchor circle)
			)
			(primitives
				(gr_poly
					(pts
						(xy 0 0.9017) (xy -0.03175 0.89916) (xy -0.0635 0.889) (xy -0.09144 0.87376) (xy -0.11684 0.85344)
						(xy -0.13716 0.82804) (xy -0.1524 0.8001) (xy -0.16256 0.76835) (xy -0.1651 0.7366) (xy -0.1651 0.44958)
						(xy -0.17272 0.44196) (xy -0.19812 0.4064) (xy -0.2032 0.39624) (xy -0.20701 0.38735) (xy -0.21209 0.37719)
						(xy -0.2159 0.36703) (xy -0.21844 0.35687) (xy -0.22225 0.34544) (xy -0.22352 0.33528) (xy -0.22606 0.32512)
						(xy -0.22733 0.31369) (xy -0.22733 0.30353) (xy -0.2286 0.2921) (xy -0.22733 0.28067) (xy -0.22733 0.27051)
						(xy -0.22606 0.25908) (xy -0.22352 0.24892) (xy -0.22225 0.23876) (xy -0.21844 0.22733) (xy -0.2159 0.21717)
						(xy -0.21209 0.20701) (xy -0.20701 0.19685) (xy -0.2032 0.18796) (xy -0.19812 0.1778) (xy -0.17272 0.14224)
						(xy -0.1651 0.13462) (xy -0.1651 -0.7366) (xy -0.16256 -0.76835) (xy -0.1524 -0.8001) (xy -0.13716 -0.82804)
						(xy -0.11684 -0.85344) (xy -0.09144 -0.87376) (xy -0.0635 -0.889) (xy -0.03175 -0.89916) (xy 0 -0.9017)
						(xy 0.03175 -0.89916) (xy 0.0635 -0.889) (xy 0.09144 -0.87376) (xy 0.11684 -0.85344) (xy 0.13716 -0.82804)
						(xy 0.1524 -0.8001) (xy 0.16256 -0.76835) (xy 0.1651 -0.7366) (xy 0.1651 0.13462) (xy 0.17272 0.14224)
						(xy 0.19812 0.1778) (xy 0.2032 0.18796) (xy 0.20701 0.19685) (xy 0.21209 0.20701) (xy 0.2159 0.21717)
						(xy 0.21844 0.22733) (xy 0.22225 0.23876) (xy 0.22352 0.24892) (xy 0.22606 0.25908) (xy 0.22733 0.27051)
						(xy 0.22733 0.28067) (xy 0.2286 0.2921) (xy 0.22733 0.30353) (xy 0.22733 0.31369) (xy 0.22606 0.32512)
						(xy 0.22352 0.33528) (xy 0.22225 0.34544) (xy 0.21844 0.35687) (xy 0.2159 0.36703) (xy 0.21209 0.37719)
						(xy 0.20701 0.38735) (xy 0.2032 0.39624) (xy 0.19812 0.4064) (xy 0.17272 0.44196) (xy 0.1651 0.44958)
						(xy 0.1651 0.7366) (xy 0.16256 0.76835) (xy 0.1524 0.8001) (xy 0.13716 0.82804) (xy 0.11684 0.85344)
						(xy 0.09144 0.87376) (xy 0.0635 0.889) (xy 0.03175 0.89916)
					)
					(width 0)
					(fill yes)
				)
			)
		)
		(pad "87" smd custom
			(at -3.450082 4.106672 180)
			(size 0.1143 0.1143)
			(layers "F.Cu" "F.Mask" "F.Paste")
			(net "M_A_CKE2")
			(options
				(clearance outline)
				(anchor circle)
			)
			(primitives
				(gr_poly
					(pts
						(xy 0 0.9017) (xy -0.03175 0.89916) (xy -0.0635 0.889) (xy -0.09144 0.87376) (xy -0.11684 0.85344)
						(xy -0.13716 0.82804) (xy -0.1524 0.8001) (xy -0.16256 0.76835) (xy -0.1651 0.7366) (xy -0.1651 0.11938)
						(xy -0.17272 0.11176) (xy -0.19812 0.0762) (xy -0.2032 0.06604) (xy -0.20701 0.05715) (xy -0.21209 0.04699)
						(xy -0.2159 0.03683) (xy -0.21844 0.02667) (xy -0.22225 0.01524) (xy -0.22352 0.00508) (xy -0.22606 -0.00508)
						(xy -0.22733 -0.01651) (xy -0.22733 -0.02667) (xy -0.2286 -0.0381) (xy -0.22733 -0.04953) (xy -0.22733 -0.05969)
						(xy -0.22606 -0.07112) (xy -0.22352 -0.08128) (xy -0.22225 -0.09144) (xy -0.21844 -0.10287) (xy -0.2159 -0.11303)
						(xy -0.21209 -0.12319) (xy -0.20701 -0.13335) (xy -0.2032 -0.14224) (xy -0.19812 -0.1524) (xy -0.17272 -0.18796)
						(xy -0.1651 -0.19558) (xy -0.1651 -0.7366) (xy -0.16256 -0.76835) (xy -0.1524 -0.8001) (xy -0.13716 -0.82804)
						(xy -0.11684 -0.85344) (xy -0.09144 -0.87376) (xy -0.0635 -0.889) (xy -0.03175 -0.89916) (xy 0 -0.9017)
						(xy 0.03175 -0.89916) (xy 0.0635 -0.889) (xy 0.09144 -0.87376) (xy 0.11684 -0.85344) (xy 0.13716 -0.82804)
						(xy 0.1524 -0.8001) (xy 0.16256 -0.76835) (xy 0.1651 -0.7366) (xy 0.1651 -0.19685) (xy 0.17272 -0.18923)
						(xy 0.17907 -0.18034) (xy 0.18669 -0.17145) (xy 0.19177 -0.16256) (xy 0.19812 -0.15367) (xy 0.20828 -0.13335)
						(xy 0.21971 -0.10287) (xy 0.22225 -0.09271) (xy 0.22479 -0.08128) (xy 0.22606 -0.07112) (xy 0.2286 -0.05969)
						(xy 0.2286 -0.01651) (xy 0.22606 -0.00508) (xy 0.22479 0.00508) (xy 0.22225 0.01651) (xy 0.21971 0.02667)
						(xy 0.20828 0.05715) (xy 0.19812 0.07747) (xy 0.19177 0.08636) (xy 0.18669 0.09525) (xy 0.17907 0.10414)
						(xy 0.17272 0.11303) (xy 0.1651 0.12065) (xy 0.1651 0.7366) (xy 0.16256 0.76835) (xy 0.1524 0.8001)
						(xy 0.13716 0.82804) (xy 0.11684 0.85344) (xy 0.09144 0.87376) (xy 0.0635 0.889) (xy 0.03175 0.89916)
					)
					(width 0)
					(fill yes)
				)
			)
		)
		(pad "88" smd custom
			(at -3.150108 -4.106672 180)
			(size 0.1143 0.1143)
			(layers "F.Cu" "F.Mask" "F.Paste")
			(net "M_A_MA15")
			(options
				(clearance outline)
				(anchor circle)
			)
			(primitives
				(gr_poly
					(pts
						(xy 0 0.9017) (xy -0.03175 0.89916) (xy -0.0635 0.889) (xy -0.09144 0.87376) (xy -0.11684 0.85344)
						(xy -0.13716 0.82804) (xy -0.1524 0.8001) (xy -0.16256 0.76835) (xy -0.1651 0.7366) (xy -0.1651 0.19685)
						(xy -0.17272 0.18923) (xy -0.17907 0.18034) (xy -0.18669 0.17145) (xy -0.19177 0.16256) (xy -0.19812 0.15367)
						(xy -0.20828 0.13335) (xy -0.21971 0.10287) (xy -0.22225 0.09271) (xy -0.22479 0.08128) (xy -0.22606 0.07112)
						(xy -0.2286 0.05969) (xy -0.2286 0.01651) (xy -0.22606 0.00508) (xy -0.22479 -0.00508) (xy -0.22225 -0.01651)
						(xy -0.21971 -0.02667) (xy -0.20828 -0.05715) (xy -0.19812 -0.07747) (xy -0.19177 -0.08636) (xy -0.18669 -0.09525)
						(xy -0.17907 -0.10414) (xy -0.17272 -0.11303) (xy -0.1651 -0.12065) (xy -0.1651 -0.7366) (xy -0.16256 -0.76835)
						(xy -0.1524 -0.8001) (xy -0.13716 -0.82804) (xy -0.11684 -0.85344) (xy -0.09144 -0.87376) (xy -0.0635 -0.889)
						(xy -0.03175 -0.89916) (xy 0 -0.9017) (xy 0.03175 -0.89916) (xy 0.0635 -0.889) (xy 0.09144 -0.87376)
						(xy 0.11684 -0.85344) (xy 0.13716 -0.82804) (xy 0.1524 -0.8001) (xy 0.16256 -0.76835) (xy 0.1651 -0.7366)
						(xy 0.1651 -0.11938) (xy 0.17272 -0.11176) (xy 0.19812 -0.0762) (xy 0.2032 -0.06604) (xy 0.20701 -0.05715)
						(xy 0.21209 -0.04699) (xy 0.2159 -0.03683) (xy 0.21844 -0.02667) (xy 0.22225 -0.01524) (xy 0.22352 -0.00508)
						(xy 0.22606 0.00508) (xy 0.22733 0.01651) (xy 0.22733 0.02667) (xy 0.2286 0.0381) (xy 0.22733 0.04953)
						(xy 0.22733 0.05969) (xy 0.22606 0.07112) (xy 0.22352 0.08128) (xy 0.22225 0.09144) (xy 0.21844 0.10287)
						(xy 0.2159 0.11303) (xy 0.21209 0.12319) (xy 0.20701 0.13335) (xy 0.2032 0.14224) (xy 0.19812 0.1524)
						(xy 0.17272 0.18796) (xy 0.1651 0.19558) (xy 0.1651 0.7366) (xy 0.16256 0.76835) (xy 0.1524 0.8001)
						(xy 0.13716 0.82804) (xy 0.11684 0.85344) (xy 0.09144 0.87376) (xy 0.0635 0.889) (xy 0.03175 0.89916)
					)
					(width 0)
					(fill yes)
				)
			)
		)
		(pad "89" smd custom
			(at -2.84988 4.106672 180)
			(size 0.1143 0.1143)
			(layers "F.Cu" "F.Mask" "F.Paste")
			(net "M_A_CKE3")
			(options
				(clearance outline)
				(anchor circle)
			)
			(primitives
				(gr_poly
					(pts
						(xy 0 0.9017) (xy -0.03175 0.89916) (xy -0.0635 0.889) (xy -0.09144 0.87376) (xy -0.11684 0.85344)
						(xy -0.13716 0.82804) (xy -0.1524 0.8001) (xy -0.16256 0.76835) (xy -0.1651 0.7366) (xy -0.1651 -0.13462)
						(xy -0.17272 -0.14224) (xy -0.19812 -0.1778) (xy -0.2032 -0.18796) (xy -0.20701 -0.19685) (xy -0.21209 -0.20701)
						(xy -0.2159 -0.21717) (xy -0.21844 -0.22733) (xy -0.22225 -0.23876) (xy -0.22352 -0.24892) (xy -0.22606 -0.25908)
						(xy -0.22733 -0.27051) (xy -0.22733 -0.28067) (xy -0.2286 -0.2921) (xy -0.22733 -0.30353) (xy -0.22733 -0.31369)
						(xy -0.22606 -0.32512) (xy -0.22352 -0.33528) (xy -0.22225 -0.34544) (xy -0.21844 -0.35687) (xy -0.2159 -0.36703)
						(xy -0.21209 -0.37719) (xy -0.20701 -0.38735) (xy -0.2032 -0.39624) (xy -0.19812 -0.4064) (xy -0.17272 -0.44196)
						(xy -0.1651 -0.44958) (xy -0.1651 -0.7366) (xy -0.16256 -0.76835) (xy -0.1524 -0.8001) (xy -0.13716 -0.82804)
						(xy -0.11684 -0.85344) (xy -0.09144 -0.87376) (xy -0.0635 -0.889) (xy -0.03175 -0.89916) (xy 0 -0.9017)
						(xy 0.03175 -0.89916) (xy 0.0635 -0.889) (xy 0.09144 -0.87376) (xy 0.11684 -0.85344) (xy 0.13716 -0.82804)
						(xy 0.1524 -0.8001) (xy 0.16256 -0.76835) (xy 0.1651 -0.7366) (xy 0.1651 -0.44958) (xy 0.17272 -0.44196)
						(xy 0.19812 -0.4064) (xy 0.2032 -0.39624) (xy 0.20701 -0.38735) (xy 0.21209 -0.37719) (xy 0.2159 -0.36703)
						(xy 0.21844 -0.35687) (xy 0.22225 -0.34544) (xy 0.22352 -0.33528) (xy 0.22606 -0.32512) (xy 0.22733 -0.31369)
						(xy 0.22733 -0.30353) (xy 0.2286 -0.2921) (xy 0.22733 -0.28067) (xy 0.22733 -0.27051) (xy 0.22606 -0.25908)
						(xy 0.22352 -0.24892) (xy 0.22225 -0.23876) (xy 0.21844 -0.22733) (xy 0.2159 -0.21717) (xy 0.21209 -0.20701)
						(xy 0.20701 -0.19685) (xy 0.2032 -0.18796) (xy 0.19812 -0.1778) (xy 0.17272 -0.14224) (xy 0.1651 -0.13462)
						(xy 0.1651 0.7366) (xy 0.16256 0.76835) (xy 0.1524 0.8001) (xy 0.13716 0.82804) (xy 0.11684 0.85344)
						(xy 0.09144 0.87376) (xy 0.0635 0.889) (xy 0.03175 0.89916)
					)
					(width 0)
					(fill yes)
				)
			)
		)
		(pad "90" smd custom
			(at -2.549906 -4.106672 180)
			(size 0.1143 0.1143)
			(layers "F.Cu" "F.Mask" "F.Paste")
			(net "M_A_MA14")
			(options
				(clearance outline)
				(anchor circle)
			)
			(primitives
				(gr_poly
					(pts
						(xy 0 0.9017) (xy -0.03175 0.89916) (xy -0.0635 0.889) (xy -0.09144 0.87376) (xy -0.11684 0.85344)
						(xy -0.13716 0.82804) (xy -0.1524 0.8001) (xy -0.16256 0.76835) (xy -0.1651 0.7366) (xy -0.1651 0.44958)
						(xy -0.17272 0.44196) (xy -0.19812 0.4064) (xy -0.2032 0.39624) (xy -0.20701 0.38735) (xy -0.21209 0.37719)
						(xy -0.2159 0.36703) (xy -0.21844 0.35687) (xy -0.22225 0.34544) (xy -0.22352 0.33528) (xy -0.22606 0.32512)
						(xy -0.22733 0.31369) (xy -0.22733 0.30353) (xy -0.2286 0.2921) (xy -0.22733 0.28067) (xy -0.22733 0.27051)
						(xy -0.22606 0.25908) (xy -0.22352 0.24892) (xy -0.22225 0.23876) (xy -0.21844 0.22733) (xy -0.2159 0.21717)
						(xy -0.21209 0.20701) (xy -0.20701 0.19685) (xy -0.2032 0.18796) (xy -0.19812 0.1778) (xy -0.17272 0.14224)
						(xy -0.1651 0.13462) (xy -0.1651 -0.7366) (xy -0.16256 -0.76835) (xy -0.1524 -0.8001) (xy -0.13716 -0.82804)
						(xy -0.11684 -0.85344) (xy -0.09144 -0.87376) (xy -0.0635 -0.889) (xy -0.03175 -0.89916) (xy 0 -0.9017)
						(xy 0.03175 -0.89916) (xy 0.0635 -0.889) (xy 0.09144 -0.87376) (xy 0.11684 -0.85344) (xy 0.13716 -0.82804)
						(xy 0.1524 -0.8001) (xy 0.16256 -0.76835) (xy 0.1651 -0.7366) (xy 0.1651 0.13462) (xy 0.17272 0.14224)
						(xy 0.19812 0.1778) (xy 0.2032 0.18796) (xy 0.20701 0.19685) (xy 0.21209 0.20701) (xy 0.2159 0.21717)
						(xy 0.21844 0.22733) (xy 0.22225 0.23876) (xy 0.22352 0.24892) (xy 0.22606 0.25908) (xy 0.22733 0.27051)
						(xy 0.22733 0.28067) (xy 0.2286 0.2921) (xy 0.22733 0.30353) (xy 0.22733 0.31369) (xy 0.22606 0.32512)
						(xy 0.22352 0.33528) (xy 0.22225 0.34544) (xy 0.21844 0.35687) (xy 0.2159 0.36703) (xy 0.21209 0.37719)
						(xy 0.20701 0.38735) (xy 0.2032 0.39624) (xy 0.19812 0.4064) (xy 0.17272 0.44196) (xy 0.1651 0.44958)
						(xy 0.1651 0.7366) (xy 0.16256 0.76835) (xy 0.1524 0.8001) (xy 0.13716 0.82804) (xy 0.11684 0.85344)
						(xy 0.09144 0.87376) (xy 0.0635 0.889) (xy 0.03175 0.89916)
					)
					(width 0)
					(fill yes)
				)
			)
		)
	)
)
